(kicad_pcb
	(version 20260206)
	(generator "pcbnew")
	(generator_version "10.0")
	(general
		(thickness 1.6)
		(legacy_teardrops no)
	)
	(paper "A4")
	(title_block
		(title "timecard-production-celestica-r4006 — R4006-B0001-02_R01.brd")
		(comment 1 "Time Appliance Project (Time Card) / footprints 812-815 of 1113")
	)
	(layers
		(0 "F.Cu" signal "TOP")
		(4 "In1.Cu" signal "L02_GND1")
		(6 "In2.Cu" signal "L03_SIG1")
		(8 "In3.Cu" signal "L04_GND2")
		(10 "In4.Cu" signal "L05_VCC1")
		(12 "In5.Cu" signal "L06_VCC2")
		(14 "In6.Cu" signal "L07_GND3")
		(16 "In7.Cu" signal "L08_SIG2")
		(18 "In8.Cu" signal "L09_GND4")
		(2 "B.Cu" signal "BOTTOM")
		(9 "F.Adhes" user "F.Adhesive")
		(11 "B.Adhes" user "B.Adhesive")
		(13 "F.Paste" user "Package Geometry/Pastemask Top")
		(15 "B.Paste" user "Package Geometry/Pastemask Bottom")
		(5 "F.SilkS" user "Ref Des/Silkscreen Top")
		(7 "B.SilkS" user "Ref Des/Silkscreen Bottom")
		(1 "F.Mask" user "Board Geometry/Soldermask Top")
		(3 "B.Mask" user "Board Geometry/Soldermask Bottom")
		(17 "Dwgs.User" user "User.Drawings")
		(19 "Cmts.User" user "User.Comments")
		(21 "Eco1.User" user "User.Eco1")
		(23 "Eco2.User" user "User.Eco2")
		(25 "Edge.Cuts" user "Board Geometry/Outline")
		(27 "Margin" user)
		(31 "F.CrtYd" user "Package Geometry/Place Bound Top")
		(29 "B.CrtYd" user "Package Geometry/Place Bound Bottom")
		(35 "F.Fab" user "Ref Des/Assembly Top")
		(33 "B.Fab" user "Ref Des/Assembly Bottom")
	)
	(footprint ""
		(layer "B.Cu")
		(at 145.1102 -68.0974 -90)
		(property "Reference" "CR7"
			(at -3.11023 -0.0508 0)
			(unlocked yes)
			(layer "B.SilkS")
			(effects
				(font
					(size 0.7874 0.5842)
					(thickness 0.1524)
				)
				(justify mirror)
			)
		)
		(property "Value" ""
			(at 0 0 90)
			(layer "B.Fab")
			(effects
				(font
					(size 1.27 1.27)
				)
				(justify mirror)
			)
		)
		(property "Device Type" "DIODE_4_V1-G122-10123-01"
			(at -0.254 2.702306 270)
			(unlocked yes)
			(layer "B.Fab")
			(hide yes)
			(effects
				(font
					(size 0.7874 0.5842)
					(thickness 0.1524)
				)
				(justify mirror)
			)
		)
		(property "User Part Number" "PARTNUM*"
			(at -0.254 3.718306 270)
			(unlocked yes)
			(layer "Cmts.User")
			(hide yes)
			(effects
				(font
					(size 0.7874 0.5842)
					(thickness 0.1524)
				)
				(justify mirror)
			)
		)
		(duplicate_pad_numbers_are_jumpers no)
		(fp_line
			(start -2.0828 1.7018)
			(end 2.0828 1.7018)
			(stroke
				(width 0.1)
				(type default)
			)
			(layer "B.SilkS")
		)
		(fp_line
			(start 2.0828 1.7018)
			(end 2.0828 -1.7018)
			(stroke
				(width 0.1)
				(type default)
			)
			(layer "B.SilkS")
		)
		(fp_line
			(start -2.0828 -1.7018)
			(end -2.0828 1.7018)
			(stroke
				(width 0.1)
				(type default)
			)
			(layer "B.SilkS")
		)
		(fp_line
			(start 2.0828 -1.7018)
			(end -2.0828 -1.7018)
			(stroke
				(width 0.1)
				(type default)
			)
			(layer "B.SilkS")
		)
		(fp_poly
			(pts
				(arc
					(start 2.6162 -1.27)
					(mid 2.6162 -0.508)
					(end 2.6162 -1.27)
				)
			)
			(stroke
				(width 0)
				(type default)
			)
			(fill yes)
			(layer "B.SilkS")
		)
		(fp_rect
			(start -2.3368 1.9304)
			(end 2.3368 -1.9304)
			(stroke
				(width 0)
				(type default)
			)
			(fill no)
			(layer "B.CrtYd")
		)
		(fp_line
			(start -0.6477 1.42875)
			(end 0.6477 1.42875)
			(stroke
				(width 0.1)
				(type default)
			)
			(layer "B.Fab")
		)
		(fp_line
			(start 0.6477 1.42875)
			(end 0.6477 -1.42875)
			(stroke
				(width 0.1)
				(type default)
			)
			(layer "B.Fab")
		)
		(fp_line
			(start -1.143 1.1811)
			(end -0.6477 1.1811)
			(stroke
				(width 0.1)
				(type default)
			)
			(layer "B.Fab")
		)
		(fp_line
			(start -0.6477 1.1811)
			(end -0.6477 0.7239)
			(stroke
				(width 0.1)
				(type default)
			)
			(layer "B.Fab")
		)
		(fp_line
			(start 0.6477 1.1811)
			(end 1.143 1.1811)
			(stroke
				(width 0.1)
				(type default)
			)
			(layer "B.Fab")
		)
		(fp_line
			(start 1.143 1.1811)
			(end 1.143 0.7239)
			(stroke
				(width 0.1)
				(type default)
			)
			(layer "B.Fab")
		)
		(fp_line
			(start -1.143 0.7239)
			(end -1.143 1.1811)
			(stroke
				(width 0.1)
				(type default)
			)
			(layer "B.Fab")
		)
		(fp_line
			(start -0.6477 0.7239)
			(end -1.143 0.7239)
			(stroke
				(width 0.1)
				(type default)
			)
			(layer "B.Fab")
		)
		(fp_line
			(start 0.6477 0.7239)
			(end 0.6477 1.1811)
			(stroke
				(width 0.1)
				(type default)
			)
			(layer "B.Fab")
		)
		(fp_line
			(start 1.143 0.7239)
			(end 0.6477 0.7239)
			(stroke
				(width 0.1)
				(type default)
			)
			(layer "B.Fab")
		)
		(fp_line
			(start 0.6477 -0.3175)
			(end 1.143 -0.3175)
			(stroke
				(width 0.1)
				(type default)
			)
			(layer "B.Fab")
		)
		(fp_line
			(start 1.143 -0.3175)
			(end 1.143 -1.1811)
			(stroke
				(width 0.1)
				(type default)
			)
			(layer "B.Fab")
		)
		(fp_line
			(start -1.143 -0.7239)
			(end -0.6477 -0.7239)
			(stroke
				(width 0.1)
				(type default)
			)
			(layer "B.Fab")
		)
		(fp_line
			(start -0.6477 -0.7239)
			(end -0.6477 -1.1811)
			(stroke
				(width 0.1)
				(type default)
			)
			(layer "B.Fab")
		)
		(fp_line
			(start -1.143 -1.1811)
			(end -1.143 -0.7239)
			(stroke
				(width 0.1)
				(type default)
			)
			(layer "B.Fab")
		)
		(fp_line
			(start -0.6477 -1.1811)
			(end -1.143 -1.1811)
			(stroke
				(width 0.1)
				(type default)
			)
			(layer "B.Fab")
		)
		(fp_line
			(start 0.6477 -1.1811)
			(end 0.6477 -0.3175)
			(stroke
				(width 0.1)
				(type default)
			)
			(layer "B.Fab")
		)
		(fp_line
			(start 1.143 -1.1811)
			(end 0.6477 -1.1811)
			(stroke
				(width 0.1)
				(type default)
			)
			(layer "B.Fab")
		)
		(fp_line
			(start -0.6477 -1.42875)
			(end -0.6477 1.42875)
			(stroke
				(width 0.1)
				(type default)
			)
			(layer "B.Fab")
		)
		(fp_line
			(start 0.6477 -1.42875)
			(end -0.6477 -1.42875)
			(stroke
				(width 0.1)
				(type default)
			)
			(layer "B.Fab")
		)
		(fp_poly
			(pts
				(arc
					(start 0.381 -0.9398)
					(mid 0.381 -0.5588)
					(end 0.381 -0.9398)
				)
			)
			(stroke
				(width 0)
				(type default)
			)
			(fill yes)
			(layer "B.Fab")
		)
		(fp_text user "3"
			(at -1.84023 1.8161 0)
			(unlocked yes)
			(layer "B.SilkS")
			(effects
				(font
					(size 0.7874 0.5842)
					(thickness 0.1524)
				)
				(justify left mirror)
			)
		)
		(fp_text user "2"
			(at 2.85877 0.8001 0)
			(unlocked yes)
			(layer "B.SilkS")
			(effects
				(font
					(size 0.7874 0.5842)
					(thickness 0.1524)
				)
				(justify left mirror)
			)
		)
		(fp_text user "4"
			(at -2.09423 -2.6289 0)
			(unlocked yes)
			(layer "B.SilkS")
			(effects
				(font
					(size 0.7874 0.5842)
					(thickness 0.1524)
				)
				(justify left mirror)
			)
		)
		(fp_text user "3"
			(at -1.76403 0.669036 0)
			(unlocked yes)
			(layer "B.Fab")
			(effects
				(font
					(size 0.7874 0.5842)
					(thickness 0.1524)
				)
				(justify left mirror)
			)
		)
		(fp_text user "2"
			(at 1.83007 0.5842 0)
			(unlocked yes)
			(layer "B.Fab")
			(effects
				(font
					(size 0.7874 0.5842)
					(thickness 0.1524)
				)
				(justify left mirror)
			)
		)
		(fp_text user "4"
			(at -1.78943 -1.261618 0)
			(unlocked yes)
			(layer "B.Fab")
			(effects
				(font
					(size 0.7874 0.5842)
					(thickness 0.1524)
				)
				(justify left mirror)
			)
		)
		(pad "1" smd rect
			(at 1.1049 -0.7493 90)
			(size 1.4478 1.0922)
			(layers "B.Cu" "B.Mask" "B.Paste")
			(net "SG")
		)
		(pad "2" smd rect
			(at 1.1049 0.9525 90)
			(size 1.4478 0.9906)
			(layers "B.Cu" "B.Mask" "B.Paste")
			(net "FT4232_FPGA_TCK")
		)
		(pad "3" smd rect
			(at -1.1049 0.9525 90)
			(size 1.4478 0.9906)
			(layers "B.Cu" "B.Mask" "B.Paste")
			(net "FT4232_FPGA_TDO")
		)
		(pad "4" smd rect
			(at -1.1049 -0.9525 90)
			(size 1.4478 0.9906)
			(layers "B.Cu" "B.Mask" "B.Paste")
			(net "Net_624")
		)
		(zone
			(layer "B.Cu")
			(hatch none 0.5)
			(connect_pads
				(clearance 0)
			)
			(min_thickness 0.25)
			(keepout
				(tracks allowed)
				(vias not_allowed)
				(pads allowed)
				(copperpour not_allowed)
				(footprints allowed)
			)
			(placement
				(enabled no)
				(sheetname "")
			)
			(fill
				(thermal_gap 0.5)
				(thermal_bridge_width 0.5)
				(island_removal_mode 0)
			)
			(polygon
				(pts
					(xy 146.4056 -67.4497) (xy 146.5453 -67.4497) (xy 146.5453 -68.4784) (xy 145.5674 -68.4784) (xy 145.5674 -68.7451)
					(xy 144.653 -68.7451) (xy 144.653 -68.4784) (xy 143.6751 -68.4784) (xy 143.6751 -67.7164) (xy 144.653 -67.7164)
					(xy 144.653 -67.4497) (xy 145.3134 -67.4497) (xy 145.3134 -67.7164) (xy 146.4056 -67.7164)
				)
			)
		)
	)
	(footprint ""
		(layer "B.Cu")
		(at 108.585 -23.876 -90)
		(property "Reference" "C246"
			(at -0.127 2.96037 270)
			(unlocked yes)
			(layer "B.SilkS")
			(effects
				(font
					(size 0.7874 0.5842)
					(thickness 0.1524)
				)
				(justify mirror)
			)
		)
		(property "Value" "VAL*"
			(at -0.0762 2.067306 270)
			(unlocked yes)
			(layer "B.Fab")
			(hide yes)
			(effects
				(font
					(size 0.7874 0.5842)
					(thickness 0.1524)
				)
				(justify mirror)
			)
		)
		(property "Device Type" "CAPACITOR-G105-0C106-BM,10UF,2A"
			(at -0.0508 1.127506 270)
			(unlocked yes)
			(layer "B.Fab")
			(hide yes)
			(effects
				(font
					(size 0.7874 0.5842)
					(thickness 0.1524)
				)
				(justify mirror)
			)
		)
		(property "User Part Number" "PARTNUM*"
			(at -0.1016 4.023106 270)
			(unlocked yes)
			(layer "Cmts.User")
			(hide yes)
			(effects
				(font
					(size 0.7874 0.5842)
					(thickness 0.1524)
				)
				(justify mirror)
			)
		)
		(property "Tolerance" "TOL*"
			(at -0.0762 3.032506 270)
			(unlocked yes)
			(layer "Cmts.User")
			(hide yes)
			(effects
				(font
					(size 0.7874 0.5842)
					(thickness 0.1524)
				)
				(justify mirror)
			)
		)
		(duplicate_pad_numbers_are_jumpers no)
		(fp_line
			(start -1.143 0.5588)
			(end -1.143 -0.5588)
			(stroke
				(width 0.1)
				(type default)
			)
			(layer "B.SilkS")
		)
		(fp_line
			(start 1.143 0.5588)
			(end -1.143 0.5588)
			(stroke
				(width 0.1)
				(type default)
			)
			(layer "B.SilkS")
		)
		(fp_line
			(start -1.143 -0.5588)
			(end 1.143 -0.5588)
			(stroke
				(width 0.1)
				(type default)
			)
			(layer "B.SilkS")
		)
		(fp_line
			(start 1.143 -0.5588)
			(end 1.143 0.5588)
			(stroke
				(width 0.1)
				(type default)
			)
			(layer "B.SilkS")
		)
		(fp_rect
			(start 1.143 0.5588)
			(end -1.143 -0.5588)
			(stroke
				(width 0)
				(type default)
			)
			(fill no)
			(layer "B.CrtYd")
		)
		(fp_line
			(start -0.508 0.3048)
			(end -0.508 -0.3048)
			(stroke
				(width 0.1)
				(type default)
			)
			(layer "B.Fab")
		)
		(fp_line
			(start 0.508 0.3048)
			(end -0.508 0.3048)
			(stroke
				(width 0.1)
				(type default)
			)
			(layer "B.Fab")
		)
		(fp_line
			(start -0.508 -0.3048)
			(end 0.508 -0.3048)
			(stroke
				(width 0.1)
				(type default)
			)
			(layer "B.Fab")
		)
		(fp_line
			(start 0.508 -0.3048)
			(end 0.508 0.3048)
			(stroke
				(width 0.1)
				(type default)
			)
			(layer "B.Fab")
		)
		(pad "1" smd rect
			(at 0.5334 0 90)
			(size 0.7112 0.6096)
			(layers "B.Cu" "B.Mask" "B.Paste")
			(net "VDD3V3_OSC_200M")
		)
		(pad "2" smd rect
			(at -0.5334 0 90)
			(size 0.7112 0.6096)
			(layers "B.Cu" "B.Mask" "B.Paste")
			(net "SG")
		)
		(zone
			(layer "B.Cu")
			(hatch none 0.5)
			(connect_pads
				(clearance 0)
			)
			(min_thickness 0.25)
			(keepout
				(tracks allowed)
				(vias not_allowed)
				(pads allowed)
				(copperpour not_allowed)
				(footprints allowed)
			)
			(placement
				(enabled no)
				(sheetname "")
			)
			(fill
				(thermal_gap 0.5)
				(thermal_bridge_width 0.5)
				(island_removal_mode 0)
			)
			(polygon
				(pts
					(xy 108.2802 -23.7998) (xy 108.8898 -23.7998) (xy 108.8898 -23.9522) (xy 108.2802 -23.9522)
				)
			)
		)
	)
	(footprint ""
		(layer "B.Cu")
		(at 124.587 -47.117)
		(property "Reference" "R92"
			(at 4.064 0.16637 0)
			(unlocked yes)
			(layer "B.SilkS")
			(effects
				(font
					(size 0.7874 0.5842)
					(thickness 0.1524)
				)
				(justify mirror)
			)
		)
		(property "Value" "VAL*"
			(at -0.02032 2.13233 0)
			(unlocked yes)
			(layer "B.Fab")
			(hide yes)
			(effects
				(font
					(size 0.7874 0.5842)
					(thickness 0.1524)
				)
				(justify mirror)
			)
		)
		(property "Tolerance" "TOL*"
			(at -0.044704 3.05435 0)
			(unlocked yes)
			(layer "Cmts.User")
			(hide yes)
			(effects
				(font
					(size 0.7874 0.5842)
					(thickness 0.1524)
				)
				(justify mirror)
			)
		)
		(property "User Part Number" "PARTNUM*"
			(at -0.02032 4.024884 0)
			(unlocked yes)
			(layer "Cmts.User")
			(hide yes)
			(effects
				(font
					(size 0.7874 0.5842)
					(thickness 0.1524)
				)
				(justify mirror)
			)
		)
		(property "Device Type" "RESISTOR-G155-100R0-J0,0OHM,-"
			(at -0.008382 1.210564 0)
			(unlocked yes)
			(layer "B.Fab")
			(hide yes)
			(effects
				(font
					(size 0.7874 0.5842)
					(thickness 0.1524)
				)
				(justify mirror)
			)
		)
		(duplicate_pad_numbers_are_jumpers no)
		(fp_line
			(start -1.143 -0.5588)
			(end 1.143 -0.5588)
			(stroke
				(width 0.1)
				(type default)
			)
			(layer "B.SilkS")
		)
		(fp_line
			(start -1.143 0.5588)
			(end -1.143 -0.5588)
			(stroke
				(width 0.1)
				(type default)
			)
			(layer "B.SilkS")
		)
		(fp_line
			(start 1.143 -0.5588)
			(end 1.143 0.5588)
			(stroke
				(width 0.1)
				(type default)
			)
			(layer "B.SilkS")
		)
		(fp_line
			(start 1.143 0.5588)
			(end -1.143 0.5588)
			(stroke
				(width 0.1)
				(type default)
			)
			(layer "B.SilkS")
		)
		(fp_poly
			(pts
				(xy 1.143 0.5588) (xy -1.143 0.5588) (xy -1.143 -0.5588) (xy 1.143 -0.5588)
			)
			(stroke
				(width 0)
				(type default)
			)
			(fill no)
			(layer "B.CrtYd")
		)
		(fp_line
			(start -0.508 -0.3048)
			(end 0.508 -0.3048)
			(stroke
				(width 0.1)
				(type default)
			)
			(layer "B.Fab")
		)
		(fp_line
			(start -0.508 0.3048)
			(end -0.508 -0.3048)
			(stroke
				(width 0.1)
				(type default)
			)
			(layer "B.Fab")
		)
		(fp_line
			(start 0.508 -0.3048)
			(end 0.508 0.3048)
			(stroke
				(width 0.1)
				(type default)
			)
			(layer "B.Fab")
		)
		(fp_line
			(start 0.508 0.3048)
			(end -0.508 0.3048)
			(stroke
				(width 0.1)
				(type default)
			)
			(layer "B.Fab")
		)
		(pad "1" smd rect
			(at 0.5334 0 180)
			(size 0.7112 0.6096)
			(layers "B.Cu" "B.Mask" "B.Paste")
			(net "R_MAC_10MHZ_RF_OUT")
		)
		(pad "2" smd rect
			(at -0.5334 0 180)
			(size 0.7112 0.6096)
			(layers "B.Cu" "B.Mask" "B.Paste")
			(net "FPGA_IN_MAC_10MHZ_OUT")
		)
		(zone
			(layer "B.Cu")
			(hatch none 0.5)
			(connect_pads
				(clearance 0)
			)
			(min_thickness 0.25)
			(keepout
				(tracks allowed)
				(vias not_allowed)
				(pads allowed)
				(copperpour not_allowed)
				(footprints allowed)
			)
			(placement
				(enabled no)
				(sheetname "")
			)
			(fill
				(thermal_gap 0.5)
				(thermal_bridge_width 0.5)
				(island_removal_mode 0)
			)
			(polygon
				(pts
					(xy 124.6632 -46.8122) (xy 124.6632 -47.4218) (xy 124.5108 -47.4218) (xy 124.5108 -46.8122)
				)
			)
		)
		(zone
			(layer "B.Cu")
			(hatch none 0.5)
			(connect_pads
				(clearance 0)
			)
			(min_thickness 0.25)
			(keepout
				(tracks not_allowed)
				(vias allowed)
				(pads allowed)
				(copperpour not_allowed)
				(footprints allowed)
			)
			(placement
				(enabled no)
				(sheetname "")
			)
			(fill
				(thermal_gap 0.5)
				(thermal_bridge_width 0.5)
				(island_removal_mode 0)
			)
			(polygon
				(pts
					(xy 124.6632 -46.8122) (xy 124.6632 -47.4218) (xy 124.5108 -47.4218) (xy 124.5108 -46.8122)
				)
			)
		)
	)
	(footprint ""
		(layer "B.Cu")
		(at 147.066 -104.648 180)
		(property "Reference" "R256"
			(at -1.016 -3.21437 0)
			(unlocked yes)
			(layer "B.SilkS")
			(effects
				(font
					(size 0.7874 0.5842)
					(thickness 0.1524)
				)
				(justify mirror)
			)
		)
		(property "Value" "VAL*"
			(at -0.02032 2.13233 180)
			(unlocked yes)
			(layer "B.Fab")
			(hide yes)
			(effects
				(font
					(size 0.7874 0.5842)
					(thickness 0.1524)
				)
				(justify mirror)
			)
		)
		(property "Tolerance" "TOL*"
			(at -0.044704 3.05435 180)
			(unlocked yes)
			(layer "Cmts.User")
			(hide yes)
			(effects
				(font
					(size 0.7874 0.5842)
					(thickness 0.1524)
				)
				(justify mirror)
			)
		)
		(property "User Part Number" "PARTNUM*"
			(at -0.02032 4.024884 180)
			(unlocked yes)
			(layer "Cmts.User")
			(hide yes)
			(effects
				(font
					(size 0.7874 0.5842)
					(thickness 0.1524)
				)
				(justify mirror)
			)
		)
		(property "Device Type" "RESISTOR-G155-11001-01,1KOHM,1%"
			(at -0.008382 1.210564 180)
			(unlocked yes)
			(layer "B.Fab")
			(hide yes)
			(effects
				(font
					(size 0.7874 0.5842)
					(thickness 0.1524)
				)
				(justify mirror)
			)
		)
		(duplicate_pad_numbers_are_jumpers no)
		(fp_line
			(start 1.143 0.5588)
			(end -1.143 0.5588)
			(stroke
				(width 0.1)
				(type default)
			)
			(layer "B.SilkS")
		)
		(fp_line
			(start 1.143 -0.5588)
			(end 1.143 0.5588)
			(stroke
				(width 0.1)
				(type default)
			)
			(layer "B.SilkS")
		)
		(fp_line
			(start -1.143 0.5588)
			(end -1.143 -0.5588)
			(stroke
				(width 0.1)
				(type default)
			)
			(layer "B.SilkS")
		)
		(fp_line
			(start -1.143 -0.5588)
			(end 1.143 -0.5588)
			(stroke
				(width 0.1)
				(type default)
			)
			(layer "B.SilkS")
		)
		(fp_rect
			(start -1.143 -0.5588)
			(end 1.143 0.5588)
			(stroke
				(width 0)
				(type default)
			)
			(fill no)
			(layer "B.CrtYd")
		)
		(fp_line
			(start 0.508 0.3048)
			(end -0.508 0.3048)
			(stroke
				(width 0.1)
				(type default)
			)
			(layer "B.Fab")
		)
		(fp_line
			(start 0.508 -0.3048)
			(end 0.508 0.3048)
			(stroke
				(width 0.1)
				(type default)
			)
			(layer "B.Fab")
		)
		(fp_line
			(start -0.508 0.3048)
			(end -0.508 -0.3048)
			(stroke
				(width 0.1)
				(type default)
			)
			(layer "B.Fab")
		)
		(fp_line
			(start -0.508 -0.3048)
			(end 0.508 -0.3048)
			(stroke
				(width 0.1)
				(type default)
			)
			(layer "B.Fab")
		)
		(pad "1" smd rect
			(at 0.5334 0)
			(size 0.7112 0.6096)
			(layers "B.Cu" "B.Mask" "B.Paste")
			(net "UNNAMED_14_OPTICAL_I143_A")
		)
		(pad "2" smd rect
			(at -0.5334 0)
			(size 0.7112 0.6096)
			(layers "B.Cu" "B.Mask" "B.Paste")
			(net "UNNAMED_14_RESISTOR_I65_2")
		)
		(zone
			(layer "B.Cu")
			(hatch none 0.5)
			(connect_pads
				(clearance 0)
			)
			(min_thickness 0.25)
			(keepout
				(tracks allowed)
				(vias not_allowed)
				(pads allowed)
				(copperpour not_allowed)
				(footprints allowed)
			)
			(placement
				(enabled no)
				(sheetname "")
			)
			(fill
				(thermal_gap 0.5)
				(thermal_bridge_width 0.5)
				(island_removal_mode 0)
			)
			(polygon
				(pts
					(xy 147.1422 -104.3432) (xy 147.1422 -104.9528) (xy 146.9898 -104.9528) (xy 146.9898 -104.3432)
				)
			)
		)
	)
)
